# T6G (Grand Teton) — schematic netlist excerpt (pin names and nets, part order shuffled) for the footprints in the layout excerpt that follows; sources: Cadence DE-HDL packaged netlist, KiCad conversion of 04192023_DAF0TMB3IC0_F0TG_MB_C_brd_V02_OCP.brd

D80  Q_LED  IC  pkg SMLF  page 256 : A = LED_PWRGD_PVDDCR_CPU0_P1_R ; C = LED_PWRGD_PVDDCR_CPU0_P1_D
C1550  Q_CAP_DIFFBUS  DIFF BUS_0.22UF 6.3V 20% X6S  pkg C0201  page 65 : \1\ = P5E_CPU0_G3_TX_C_DN<14> ; \2\ = P5E_CPU0_G3_TX_DN<14>
C196  Q_CAP  1000PF 50V 5% EMPTY  pkg 0402  page 207 : A = PWRGD_PVDD11_S3_P0_R ; B = GND

(kicad_pcb
	(version 20260206)
	(generator "pcbnew")
	(generator_version "10.0")
	(general
		(thickness 1.6)
		(legacy_teardrops no)
	)
	(paper "A4")
	(title_block
		(title "04192023_DAF0TMB3IC0_F0TG_MB_C_brd_V02_OCP.brd")
		(comment 1 "Grand Teton / footprints 1554-1556 of 8354")
	)
	(layers
		(0 "F.Cu" signal "TOP")
		(4 "In1.Cu" signal "GND")
		(6 "In2.Cu" signal "IN1")
		(8 "In3.Cu" signal "GND1")
		(10 "In4.Cu" signal "IN2")
		(12 "In5.Cu" signal "GND2")
		(14 "In6.Cu" signal "IN3")
		(16 "In7.Cu" signal "GND3")
		(18 "In8.Cu" signal "VCC")
		(20 "In9.Cu" signal "VCC1")
		(22 "In10.Cu" signal "GND4")
		(24 "In11.Cu" signal "IN4")
		(26 "In12.Cu" signal "GND5")
		(28 "In13.Cu" signal "IN5")
		(30 "In14.Cu" signal "GND6")
		(32 "In15.Cu" signal "IN6")
		(34 "In16.Cu" signal "GND7")
		(2 "B.Cu" signal "BOTTOM")
		(9 "F.Adhes" user "F.Adhesive")
		(11 "B.Adhes" user "B.Adhesive")
		(13 "F.Paste" user "Package Geometry/Pastemask Top")
		(15 "B.Paste" user "Package Geometry/Pastemask Bottom")
		(5 "F.SilkS" user "Ref Des/Silkscreen Top")
		(7 "B.SilkS" user "Ref Des/Silkscreen Bottom")
		(1 "F.Mask" user "Board Geometry/Soldermask Top")
		(3 "B.Mask" user "Board Geometry/Soldermask Bottom")
		(17 "Dwgs.User" user "User.Drawings")
		(19 "Cmts.User" user "User.Comments")
		(21 "Eco1.User" user "User.Eco1")
		(23 "Eco2.User" user "User.Eco2")
		(25 "Edge.Cuts" user "Board Geometry/Outline")
		(27 "Margin" user)
		(31 "F.CrtYd" user "Package Geometry/Place Bound Top")
		(29 "B.CrtYd" user "Package Geometry/Place Bound Bottom")
		(35 "F.Fab" user "Ref Des/Assembly Top")
		(33 "B.Fab" user "Ref Des/Assembly Bottom")
	)
	(footprint ""
		(layer "F.Cu")
		(at 414.331912 -364.781592 180)
		(property "Reference" "C196"
			(at 0 0 180)
			(layer "F.SilkS")
			(hide yes)
			(effects
				(font
					(size 1.27 1.27)
				)
			)
		)
		(property "Value" ""
			(at 0 0 180)
			(layer "F.Fab")
			(effects
				(font
					(size 1.27 1.27)
				)
			)
		)
		(duplicate_pad_numbers_are_jumpers no)
		(fp_line
			(start 0.7874 0.4064)
			(end -0.7874 0.4064)
			(stroke
				(width 0.1524)
				(type default)
			)
			(layer "F.SilkS")
		)
		(fp_line
			(start 0.7874 -0.4064)
			(end 0.7874 0.4064)
			(stroke
				(width 0.1524)
				(type default)
			)
			(layer "F.SilkS")
		)
		(fp_line
			(start -0.7874 0.4064)
			(end -0.7874 -0.4064)
			(stroke
				(width 0.1524)
				(type default)
			)
			(layer "F.SilkS")
		)
		(fp_line
			(start -0.7874 -0.4064)
			(end 0.7874 -0.4064)
			(stroke
				(width 0.1524)
				(type default)
			)
			(layer "F.SilkS")
		)
		(fp_line
			(start 0.67945 0.3048)
			(end 0.120396 0.3048)
			(stroke
				(width 0.1)
				(type default)
			)
			(layer "F.Fab")
		)
		(fp_line
			(start 0.67945 -0.3048)
			(end 0.67945 0.3048)
			(stroke
				(width 0.1)
				(type default)
			)
			(layer "F.Fab")
		)
		(fp_line
			(start 0.12065 -0.2794)
			(end 0.12065 -0.3048)
			(stroke
				(width 0.1)
				(type default)
			)
			(layer "F.Fab")
		)
		(fp_line
			(start 0.12065 -0.3048)
			(end 0.67945 -0.3048)
			(stroke
				(width 0.1)
				(type default)
			)
			(layer "F.Fab")
		)
		(fp_line
			(start 0.120396 0.3048)
			(end 0.120396 0.2794)
			(stroke
				(width 0.1)
				(type default)
			)
			(layer "F.Fab")
		)
		(fp_line
			(start 0.120396 0.2794)
			(end -0.12065 0.2794)
			(stroke
				(width 0.1)
				(type default)
			)
			(layer "F.Fab")
		)
		(fp_line
			(start -0.12065 0.3048)
			(end -0.67945 0.3048)
			(stroke
				(width 0.1)
				(type default)
			)
			(layer "F.Fab")
		)
		(fp_line
			(start -0.12065 0.2794)
			(end -0.12065 0.3048)
			(stroke
				(width 0.1)
				(type default)
			)
			(layer "F.Fab")
		)
		(fp_line
			(start -0.12065 -0.2794)
			(end 0.12065 -0.2794)
			(stroke
				(width 0.1)
				(type default)
			)
			(layer "F.Fab")
		)
		(fp_line
			(start -0.12065 -0.305054)
			(end -0.12065 -0.2794)
			(stroke
				(width 0.1)
				(type default)
			)
			(layer "F.Fab")
		)
		(fp_line
			(start -0.67945 0.3048)
			(end -0.67945 -0.305054)
			(stroke
				(width 0.1)
				(type default)
			)
			(layer "F.Fab")
		)
		(fp_line
			(start -0.67945 -0.305054)
			(end -0.12065 -0.305054)
			(stroke
				(width 0.1)
				(type default)
			)
			(layer "F.Fab")
		)
		(pad "1" smd circle
			(at -0.40005 0 180)
			(size 0 0)
			(layers "F.Cu" "F.Mask" "F.Paste")
			(net "PWRGD_PVDD11_S3_P0_R")
		)
		(pad "2" smd circle
			(at 0.40005 0 180)
			(size 0 0)
			(layers "F.Cu" "F.Mask" "F.Paste")
			(net "GND")
		)
	)
	(footprint ""
		(layer "F.Cu")
		(at 336.827876 -70.098412 90)
		(property "Reference" "D80"
			(at -3.934714 -0.691642 90)
			(unlocked yes)
			(layer "F.SilkS")
			(effects
				(font
					(size 0.7874 0.5842)
					(thickness 0.1524)
				)
				(justify left)
			)
		)
		(property "Value" ""
			(at 0 0 90)
			(layer "F.Fab")
			(effects
				(font
					(size 1.27 1.27)
				)
			)
		)
		(duplicate_pad_numbers_are_jumpers no)
		(fp_line
			(start 1.16078 -0.4826)
			(end 1.16078 0.4826)
			(stroke
				(width 0.1524)
				(type default)
			)
			(layer "F.SilkS")
		)
		(fp_line
			(start 1.03378 -0.4826)
			(end 1.03378 0.4826)
			(stroke
				(width 0.1524)
				(type default)
			)
			(layer "F.SilkS")
		)
		(fp_line
			(start 0.90678 -0.4826)
			(end 0.90678 0.4826)
			(stroke
				(width 0.1524)
				(type default)
			)
			(layer "F.SilkS")
		)
		(fp_line
			(start -0.64008 -0.4826)
			(end 1.16078 -0.4826)
			(stroke
				(width 0.1524)
				(type default)
			)
			(layer "F.SilkS")
		)
		(fp_line
			(start -0.79248 -0.4826)
			(end 1.03378 -0.4826)
			(stroke
				(width 0.1524)
				(type default)
			)
			(layer "F.SilkS")
		)
		(fp_line
			(start -0.89408 -0.4826)
			(end 0.90678 -0.4826)
			(stroke
				(width 0.1524)
				(type default)
			)
			(layer "F.SilkS")
		)
		(fp_line
			(start 1.16078 0.4826)
			(end -0.64008 0.4826)
			(stroke
				(width 0.1524)
				(type default)
			)
			(layer "F.SilkS")
		)
		(fp_line
			(start 1.03378 0.4826)
			(end -0.79248 0.4826)
			(stroke
				(width 0.1524)
				(type default)
			)
			(layer "F.SilkS")
		)
		(fp_line
			(start 0.90678 0.4826)
			(end -0.90678 0.4826)
			(stroke
				(width 0.1524)
				(type default)
			)
			(layer "F.SilkS")
		)
		(fp_line
			(start -0.90678 0.4826)
			(end -0.90678 -0.4699)
			(stroke
				(width 0.1524)
				(type default)
			)
			(layer "F.SilkS")
		)
		(fp_line
			(start 0.499872 -0.249936)
			(end 0.499872 0.249936)
			(stroke
				(width 0.1)
				(type default)
			)
			(layer "F.Fab")
		)
		(fp_line
			(start -0.499872 -0.249936)
			(end 0.499872 -0.249936)
			(stroke
				(width 0.1)
				(type default)
			)
			(layer "F.Fab")
		)
		(fp_line
			(start 0.499872 0.249936)
			(end -0.499872 0.249936)
			(stroke
				(width 0.1)
				(type default)
			)
			(layer "F.Fab")
		)
		(fp_line
			(start -0.499872 0.249936)
			(end -0.499872 -0.249936)
			(stroke
				(width 0.1)
				(type default)
			)
			(layer "F.Fab")
		)
		(pad "A" smd rect
			(at -0.47498 0 90)
			(size 0.6096 0.7112)
			(layers "F.Cu" "F.Mask" "F.Paste")
			(net "LED_PWRGD_PVDDCR_CPU0_P1_R")
		)
		(pad "C" smd rect
			(at 0.47498 0 90)
			(size 0.6096 0.7112)
			(layers "F.Cu" "F.Mask" "F.Paste")
			(net "LED_PWRGD_PVDDCR_CPU0_P1_D")
		)
	)
	(footprint ""
		(layer "F.Cu")
		(at 392.801348 -17.624298 90)
		(property "Reference" "C1550"
			(at 0 0 90)
			(layer "F.SilkS")
			(hide yes)
			(effects
				(font
					(size 1.27 1.27)
				)
			)
		)
		(property "Value" ""
			(at 0 0 90)
			(layer "F.Fab")
			(effects
				(font
					(size 1.27 1.27)
				)
			)
		)
		(duplicate_pad_numbers_are_jumpers no)
		(fp_line
			(start 0.299974 -0.150114)
			(end 0.299974 0.150114)
			(stroke
				(width 0.1)
				(type default)
			)
			(layer "F.Fab")
		)
		(fp_line
			(start -0.299974 -0.150114)
			(end 0.299974 -0.150114)
			(stroke
				(width 0.1)
				(type default)
			)
			(layer "F.Fab")
		)
		(fp_line
			(start 0.299974 0.150114)
			(end -0.299974 0.150114)
			(stroke
				(width 0.1)
				(type default)
			)
			(layer "F.Fab")
		)
		(fp_line
			(start -0.299974 0.150114)
			(end -0.299974 -0.150114)
			(stroke
				(width 0.1)
				(type default)
			)
			(layer "F.Fab")
		)
		(pad "1" smd rect
			(at -0.2667 0 90)
			(size 0.3048 0.381)
			(layers "F.Cu" "F.Mask" "F.Paste")
			(net "P5E_CPU0_G3_TX_C_DN<14>")
		)
		(pad "2" smd rect
			(at 0.2667 0 90)
			(size 0.3048 0.381)
			(layers "F.Cu" "F.Mask" "F.Paste")
			(net "P5E_CPU0_G3_TX_DN<14>")
		)
	)
)
